(kicad_pcb
	(version 20241229)
	(generator "pcbnew")
	(generator_version "9.0")
	(general
		(thickness 1.63)
		(legacy_teardrops no)
	)
	(paper "A4")
	(title_block
		(title "CM4 Baseboard")
		(date "2026-01-05")
		(rev "1.1.1")
		(company "Antmicro Ltd")
		(comment 1 "www.antmicro.com")
		(comment 9 "footprints 229-232 of 506")
	)
	(layers
		(0 "F.Cu" signal)
		(4 "In1.Cu" power)
		(6 "In2.Cu" power)
		(8 "In3.Cu" signal)
		(10 "In4.Cu" signal)
		(2 "B.Cu" signal)
		(9 "F.Adhes" user "F.Adhesive")
		(11 "B.Adhes" user "B.Adhesive")
		(13 "F.Paste" user)
		(15 "B.Paste" user)
		(5 "F.SilkS" user "F.Silkscreen")
		(7 "B.SilkS" user "B.Silkscreen")
		(1 "F.Mask" user)
		(3 "B.Mask" user)
		(17 "Dwgs.User" user "User.Drawings")
		(19 "Cmts.User" user "User.Comments")
		(21 "Eco1.User" user "User.Eco1")
		(23 "Eco2.User" user "User.Eco2")
		(25 "Edge.Cuts" user)
		(27 "Margin" user)
		(31 "F.CrtYd" user "F.Courtyard")
		(29 "B.CrtYd" user "B.Courtyard")
		(35 "F.Fab" user)
		(33 "B.Fab" user)
	)
	(footprint "antmicro-footprints:QFN-28-1EP_6x6mm_P0.65mm_EP3.7x3.7mm"
		(layer "F.Cu")
		(at 95.217962 152.7915 -90)
		(property "Reference" "U204"
			(at 0.255 -4.44 90)
			(layer "F.SilkS")
			(effects
				(font
					(size 0.7 0.7)
					(thickness 0.15)
				)
				(justify right bottom)
			)
		)
		(property "Value" "MCP23017T-E_QFN"
			(at 0.15 4.95 90)
			(layer "F.Fab")
			(effects
				(font
					(size 0.7 0.7)
					(thickness 0.15)
				)
				(justify right bottom)
			)
		)
		(property "Datasheet" "https://ww1.microchip.com/downloads/aemDocuments/documents/APID/ProductDocuments/DataSheets/MCP23017-Data-Sheet-DS20001952.pdf"
			(at 0 0 270)
			(layer "F.Fab")
			(hide yes)
			(effects
				(font
					(size 1.27 1.27)
					(thickness 0.15)
				)
			)
		)
		(property "Manufacturer" "Microchip Technology"
			(at 0 0 270)
			(unlocked yes)
			(layer "F.Fab")
			(hide yes)
			(effects
				(font
					(size 1 1)
					(thickness 0.15)
				)
			)
		)
		(property "MPN" "MCP23017T-E/ML"
			(at 0 0 270)
			(unlocked yes)
			(layer "F.Fab")
			(hide yes)
			(effects
				(font
					(size 1 1)
					(thickness 0.15)
				)
			)
		)
		(property "Author" "Antmicro"
			(at 0 0 270)
			(unlocked yes)
			(layer "F.Fab")
			(hide yes)
			(effects
				(font
					(size 1 1)
					(thickness 0.15)
				)
			)
		)
		(property "License" "Apache-2.0"
			(at 0 0 270)
			(unlocked yes)
			(layer "F.Fab")
			(hide yes)
			(effects
				(font
					(size 1 1)
					(thickness 0.15)
				)
			)
		)
		(sheetname "/Compute module/")
		(sheetfile "compute-module.kicad_sch")
		(attr smd)
		(fp_line
			(start -3 3)
			(end -2.5 3)
			(stroke
				(width 0.15)
				(type solid)
			)
			(layer "F.SilkS")
		)
		(fp_line
			(start -3 3)
			(end -3 2.5)
			(stroke
				(width 0.15)
				(type solid)
			)
			(layer "F.SilkS")
		)
		(fp_line
			(start 3 3)
			(end 2.5 3)
			(stroke
				(width 0.15)
				(type solid)
			)
			(layer "F.SilkS")
		)
		(fp_line
			(start 3 3)
			(end 3 2.5)
			(stroke
				(width 0.15)
				(type solid)
			)
			(layer "F.SilkS")
		)
		(fp_line
			(start -3 -3)
			(end -3 -2.5)
			(stroke
				(width 0.15)
				(type solid)
			)
			(layer "F.SilkS")
		)
		(fp_line
			(start -3 -3)
			(end -2.5 -3)
			(stroke
				(width 0.15)
				(type solid)
			)
			(layer "F.SilkS")
		)
		(fp_line
			(start 3 -3)
			(end 3 -2.5)
			(stroke
				(width 0.15)
				(type solid)
			)
			(layer "F.SilkS")
		)
		(fp_line
			(start 3 -3)
			(end 2.5 -3)
			(stroke
				(width 0.15)
				(type solid)
			)
			(layer "F.SilkS")
		)
		(fp_circle
			(center -3.3 -2.4)
			(end -3.25 -2.4)
			(stroke
				(width 0.15)
				(type solid)
			)
			(fill yes)
			(layer "F.SilkS")
		)
		(fp_poly
			(pts
				(xy -1.17 -1.17) (xy 1.17 -1.17) (xy 1.17 1.17) (xy -1.17 1.17)
			)
			(stroke
				(width 0.01)
				(type solid)
			)
			(fill yes)
			(layer "F.Paste")
		)
		(fp_rect
			(start -3.5 -3.5)
			(end 3.5 3.5)
			(stroke
				(width 0.05)
				(type solid)
			)
			(fill no)
			(layer "F.CrtYd")
		)
		(fp_line
			(start -3 -1)
			(end -1 -3)
			(stroke
				(width 0.15)
				(type solid)
			)
			(layer "F.Fab")
		)
		(fp_rect
			(start -3 -3)
			(end 3 3)
			(stroke
				(width 0.15)
				(type solid)
			)
			(fill no)
			(layer "F.Fab")
		)
		(fp_text user "Author: Antmicro"
			(at -3.96 7.94 270)
			(layer "F.Fab")
			(effects
				(font
					(size 0.7 0.7)
					(thickness 0.15)
				)
				(justify left bottom)
			)
		)
		(fp_text user "${REFERENCE}"
			(at -3.96 6.74 270)
			(layer "F.Fab")
			(effects
				(font
					(size 0.7 0.7)
					(thickness 0.15)
				)
				(justify left bottom)
			)
		)
		(fp_text user "License: Apache-2.0"
			(at -3.96 9.14 270)
			(layer "F.Fab")
			(effects
				(font
					(size 0.7 0.7)
					(thickness 0.15)
				)
				(justify left bottom)
			)
		)
		(pad "1" smd rect
			(at -2.85 -1.95 270)
			(size 1 0.31)
			(layers "F.Cu" "F.Mask" "F.Paste")
			(net 118 "/Compute module/SDIO.CD")
			(pinfunction "GPB4")
			(pintype "bidirectional")
		)
		(pad "2" smd rect
			(at -2.85 -1.3 270)
			(size 1 0.31)
			(layers "F.Cu" "F.Mask" "F.Paste")
			(net 380 "/Compute module/NVMe_EN")
			(pinfunction "GPB5")
			(pintype "bidirectional")
		)
		(pad "3" smd rect
			(at -2.85 -0.65 270)
			(size 1 0.31)
			(layers "F.Cu" "F.Mask" "F.Paste")
			(net 284 "Net-(U204-GPB6)")
			(pinfunction "GPB6")
			(pintype "bidirectional")
		)
		(pad "4" smd rect
			(at -2.85 0 270)
			(size 1 0.31)
			(layers "F.Cu" "F.Mask" "F.Paste")
			(net 386 "/Compute module/~{POE EN}")
			(pinfunction "GPB7")
			(pintype "output")
		)
		(pad "5" smd rect
			(at -2.85 0.65 270)
			(size 1 0.31)
			(layers "F.Cu" "F.Mask" "F.Paste")
			(net 9 "+3V3")
			(pinfunction "VDD")
			(pintype "power_in")
		)
		(pad "6" smd rect
			(at -2.85 1.3 270)
			(size 1 0.31)
			(layers "F.Cu" "F.Mask" "F.Paste")
			(net 3 "GND")
			(pinfunction "VSS")
			(pintype "power_in")
		)
		(pad "7" smd rect
			(at -2.85 1.95 270)
			(size 1 0.31)
			(layers "F.Cu" "F.Mask" "F.Paste")
			(net 387 "unconnected-(U204-NC-Pad7)")
			(pinfunction "NC")
			(pintype "no_connect")
		)
		(pad "8" smd rect
			(at -1.95 2.85 270)
			(size 0.31 1)
			(layers "F.Cu" "F.Mask" "F.Paste")
			(net 142 "/CSI/I_{2}C1.SCL")
			(pinfunction "SCK")
			(pintype "input")
		)
		(pad "9" smd rect
			(at -1.3 2.85 270)
			(size 0.31 1)
			(layers "F.Cu" "F.Mask" "F.Paste")
			(net 143 "/CSI/I_{2}C1.SDA")
			(pinfunction "SDA")
			(pintype "bidirectional")
		)
		(pad "10" smd rect
			(at -0.65 2.85 270)
			(size 0.31 1)
			(layers "F.Cu" "F.Mask" "F.Paste")
			(net 388 "unconnected-(U204-NC-Pad10)")
			(pinfunction "NC")
			(pintype "no_connect")
		)
		(pad "11" smd rect
			(at 0 2.85 270)
			(size 0.31 1)
			(layers "F.Cu" "F.Mask" "F.Paste")
			(net 349 "Net-(U204-A0)")
			(pinfunction "A0")
			(pintype "input")
		)
		(pad "12" smd rect
			(at 0.65 2.85 270)
			(size 0.31 1)
			(layers "F.Cu" "F.Mask" "F.Paste")
			(net 346 "Net-(U204-A1)")
			(pinfunction "A1")
			(pintype "input")
		)
		(pad "13" smd rect
			(at 1.3 2.85 270)
			(size 0.31 1)
			(layers "F.Cu" "F.Mask" "F.Paste")
			(net 345 "Net-(U204-A2)")
			(pinfunction "A2")
			(pintype "input")
		)
		(pad "14" smd rect
			(at 1.95 2.85 270)
			(size 0.31 1)
			(layers "F.Cu" "F.Mask" "F.Paste")
			(net 348 "Net-(U204-~{RESET})")
			(pinfunction "~{RESET}")
			(pintype "input")
		)
		(pad "15" smd rect
			(at 2.85 1.95 270)
			(size 1 0.31)
			(layers "F.Cu" "F.Mask" "F.Paste")
			(net 389 "unconnected-(U204-INTB-Pad15)")
			(pinfunction "INTB")
			(pintype "output+no_connect")
		)
		(pad "16" smd rect
			(at 2.85 1.3 270)
			(size 1 0.31)
			(layers "F.Cu" "F.Mask" "F.Paste")
			(net 347 "/Compute module/ExpanderINT")
			(pinfunction "INTA")
			(pintype "output")
		)
		(pad "17" smd rect
			(at 2.85 0.65 270)
			(size 1 0.31)
			(layers "F.Cu" "F.Mask" "F.Paste")
			(net 285 "/Compute module/NFC.EN")
			(pinfunction "GPA0")
			(pintype "bidirectional")
		)
		(pad "18" smd rect
			(at 2.85 0 270)
			(size 1 0.31)
			(layers "F.Cu" "F.Mask" "F.Paste")
			(net 286 "/Compute module/NFC.IRQ")
			(pinfunction "GPA1")
			(pintype "bidirectional")
		)
		(pad "19" smd rect
			(at 2.85 -0.65 270)
			(size 1 0.31)
			(layers "F.Cu" "F.Mask" "F.Paste")
			(net 287 "/Compute module/NFC.DWL_REQ")
			(pinfunction "GPA2")
			(pintype "bidirectional")
		)
		(pad "20" smd rect
			(at 2.85 -1.3 270)
			(size 1 0.31)
			(layers "F.Cu" "F.Mask" "F.Paste")
			(net 276 "Net-(U204-GPA3)")
			(pinfunction "GPA3")
			(pintype "bidirectional")
		)
		(pad "21" smd rect
			(at 2.85 -1.95 270)
			(size 1 0.31)
			(layers "F.Cu" "F.Mask" "F.Paste")
			(net 121 "/Compute module/DSICtrl.~{IRQ2}")
			(pinfunction "GPA4")
			(pintype "bidirectional")
		)
		(pad "22" smd rect
			(at 1.95 -2.85 270)
			(size 0.31 1)
			(layers "F.Cu" "F.Mask" "F.Paste")
			(net 120 "/Compute module/DSICtrl.IRQ1")
			(pinfunction "GPA5")
			(pintype "bidirectional")
		)
		(pad "23" smd rect
			(at 1.3 -2.85 270)
			(size 0.31 1)
			(layers "F.Cu" "F.Mask" "F.Paste")
			(net 122 "/Compute module/DSICtrl.EN")
			(pinfunction "GPA6")
			(pintype "bidirectional")
		)
		(pad "24" smd rect
			(at 0.65 -2.85 270)
			(size 0.31 1)
			(layers "F.Cu" "F.Mask" "F.Paste")
			(net 123 "/Compute module/DSICtrl.~{RST}")
			(pinfunction "GPA7")
			(pintype "output")
		)
		(pad "25" smd rect
			(at 0 -2.85 270)
			(size 0.31 1)
			(layers "F.Cu" "F.Mask" "F.Paste")
			(net 125 "/Compute module/DSICtrl.GPIO")
			(pinfunction "GPB0")
			(pintype "bidirectional")
		)
		(pad "26" smd rect
			(at -0.65 -2.85 270)
			(size 0.31 1)
			(layers "F.Cu" "F.Mask" "F.Paste")
			(net 369 "/CSI/CamCtrl.EN")
			(pinfunction "GPB1")
			(pintype "bidirectional")
		)
		(pad "27" smd rect
			(at -1.3 -2.85 270)
			(size 0.31 1)
			(layers "F.Cu" "F.Mask" "F.Paste")
			(net 274 "/CSI/CamCtrl.VSYNC0")
			(pinfunction "GPB2")
			(pintype "bidirectional")
		)
		(pad "28" smd rect
			(at -1.95 -2.85 270)
			(size 0.31 1)
			(layers "F.Cu" "F.Mask" "F.Paste")
			(net 275 "/CSI/CamCtrl.VSYNC1")
			(pinfunction "GPB3")
			(pintype "bidirectional")
		)
		(pad "29" smd rect
			(at 0 0 270)
			(size 3.7 3.7)
			(layers "F.Cu" "F.Mask")
			(net 3 "GND")
			(pinfunction "EP")
			(pintype "power_in")
		)
	)
	(footprint "antmicro-footprints:R_0402_1005Metric"
		(layer "F.Cu")
		(at 131.937962 161.4965 90)
		(descr "Resistor SMD 0402")
		(tags "resistor SMD 0402")
		(property "Reference" "R601"
			(at -1.23 -1.91 90)
			(layer "F.SilkS")
			(effects
				(font
					(size 0.7 0.7)
					(thickness 0.15)
				)
				(justify left bottom)
			)
		)
		(property "Value" "R_100k_0402"
			(at -1.011843 1.772047 90)
			(layer "F.Fab")
			(effects
				(font
					(size 0.7 0.7)
					(thickness 0.15)
				)
				(justify left bottom)
			)
		)
		(property "Datasheet" "https://www.bourns.com/docs/product-datasheets/cr.pdf"
			(at 0 0 90)
			(layer "F.Fab")
			(hide yes)
			(effects
				(font
					(size 1.27 1.27)
					(thickness 0.15)
				)
			)
		)
		(property "Manufacturer" "Bourns"
			(at 0 0 90)
			(unlocked yes)
			(layer "F.Fab")
			(hide yes)
			(effects
				(font
					(size 1 1)
					(thickness 0.15)
				)
			)
		)
		(property "MPN" "CR0402-FX-1003GLF"
			(at 0 0 90)
			(unlocked yes)
			(layer "F.Fab")
			(hide yes)
			(effects
				(font
					(size 1 1)
					(thickness 0.15)
				)
			)
		)
		(property "Val" "100k"
			(at 0 0 90)
			(unlocked yes)
			(layer "F.Fab")
			(hide yes)
			(effects
				(font
					(size 1 1)
					(thickness 0.15)
				)
			)
		)
		(property "License" "Apache-2.0"
			(at 0 0 90)
			(unlocked yes)
			(layer "F.Fab")
			(hide yes)
			(effects
				(font
					(size 1 1)
					(thickness 0.15)
				)
			)
		)
		(property "Author" "Antmicro"
			(at 0 0 90)
			(unlocked yes)
			(layer "F.Fab")
			(hide yes)
			(effects
				(font
					(size 1 1)
					(thickness 0.15)
				)
			)
		)
		(property "Tolerance" "1%"
			(at 0 0 90)
			(unlocked yes)
			(layer "F.Fab")
			(hide yes)
			(effects
				(font
					(size 1 1)
					(thickness 0.15)
				)
			)
		)
		(sheetname "/CSI/")
		(sheetfile "csi.kicad_sch")
		(attr smd)
		(fp_rect
			(start -0.925 -0.47)
			(end 0.925 0.47)
			(stroke
				(width 0.05)
				(type default)
			)
			(fill no)
			(layer "F.CrtYd")
		)
		(fp_rect
			(start -0.5 -0.25)
			(end 0.5 0.25)
			(stroke
				(width 0.15)
				(type solid)
			)
			(fill no)
			(layer "F.Fab")
		)
		(fp_text user "Author: Antmicro"
			(at -0.95 4.169 90)
			(layer "F.Fab")
			(effects
				(font
					(size 0.7 0.7)
					(thickness 0.15)
				)
				(justify left bottom)
			)
		)
		(fp_text user "${REFERENCE}"
			(at -0.95 3.168 90)
			(layer "F.Fab")
			(effects
				(font
					(size 0.7 0.7)
					(thickness 0.15)
				)
				(justify left bottom)
			)
		)
		(fp_text user "License: Apache-2.0"
			(at -0.95 5.169 90)
			(layer "F.Fab")
			(effects
				(font
					(size 0.7 0.7)
					(thickness 0.15)
				)
				(justify left bottom)
			)
		)
		(pad "1" smd roundrect
			(at -0.48 0 90)
			(size 0.59 0.64)
			(layers "F.Cu" "F.Mask" "F.Paste")
			(roundrect_rratio 0.25)
			(net 3 "GND")
			(pintype "passive")
		)
		(pad "2" smd roundrect
			(at 0.48 0 90)
			(size 0.59 0.64)
			(layers "F.Cu" "F.Mask" "F.Paste")
			(roundrect_rratio 0.25)
			(net 369 "/CSI/CamCtrl.EN")
			(pintype "passive")
		)
	)
	(footprint "antmicro-footprints:TP_SMD_0.75mm"
		(layer "F.Cu")
		(at 95.877962 148.7365)
		(property "Reference" "TP211"
			(at 3.847038 2.5885 90)
			(layer "F.SilkS")
			(effects
				(font
					(size 0.7 0.7)
					(thickness 0.15)
				)
				(justify left bottom)
			)
		)
		(property "Value" "TP_0.75mm_SMD"
			(at 0 1.2 0)
			(layer "F.Fab")
			(effects
				(font
					(size 0.7 0.7)
					(thickness 0.15)
				)
				(justify left bottom)
			)
		)
		(property "Author" "Antmicro"
			(at 0 0 0)
			(unlocked yes)
			(layer "F.Fab")
			(hide yes)
			(effects
				(font
					(size 1 1)
					(thickness 0.15)
				)
			)
		)
		(property "License" "Apache-2.0"
			(at 0 0 0)
			(unlocked yes)
			(layer "F.Fab")
			(hide yes)
			(effects
				(font
					(size 1 1)
					(thickness 0.15)
				)
			)
		)
		(property "MPN" ""
			(at 0 0 0)
			(unlocked yes)
			(layer "F.Fab")
			(hide yes)
			(effects
				(font
					(size 1 1)
					(thickness 0.15)
				)
			)
		)
		(property "Manufacturer" ""
			(at 0 0 0)
			(unlocked yes)
			(layer "F.Fab")
			(hide yes)
			(effects
				(font
					(size 1 1)
					(thickness 0.15)
				)
			)
		)
		(sheetname "/Compute module/")
		(sheetfile "compute-module.kicad_sch")
		(attr exclude_from_pos_files exclude_from_bom)
		(fp_circle
			(center 0 0)
			(end 0.475 0)
			(stroke
				(width 0.05)
				(type default)
			)
			(fill no)
			(layer "F.CrtYd")
		)
		(fp_text user "${REFERENCE}"
			(at -0.4 2.7 0)
			(layer "F.Fab")
			(effects
				(font
					(size 0.7 0.7)
					(thickness 0.15)
				)
				(justify left bottom)
			)
		)
		(fp_text user "Author: Antmicro"
			(at -0.4 3.901 0)
			(layer "F.Fab")
			(effects
				(font
					(size 0.7 0.7)
					(thickness 0.15)
				)
				(justify left bottom)
			)
		)
		(fp_text user "License: Apache-2.0"
			(at -0.4 5.101 0)
			(layer "F.Fab")
			(effects
				(font
					(size 0.7 0.7)
					(thickness 0.15)
				)
				(justify left bottom)
			)
		)
		(pad "1" smd circle
			(at 0 0)
			(size 0.75 0.75)
			(layers "F.Cu" "F.Mask")
			(net 284 "Net-(U204-GPB6)")
			(pinfunction "1")
			(pintype "passive")
		)
	)
	(footprint "antmicro-footprints:FB_0402_1005Metric"
		(layer "F.Cu")
		(at 92.817962 131.4665 -90)
		(descr "Ferrite Bead SMD 0402")
		(tags "ferrite bead SMD 0402")
		(property "Reference" "FB902"
			(at -4.59 -0.4 90)
			(layer "F.SilkS")
			(effects
				(font
					(size 0.7 0.7)
					(thickness 0.15)
				)
				(justify right bottom)
			)
		)
		(property "Value" "FB_120Z_1.3A_Murata-BLM15PD_0402"
			(at 0 1.4 90)
			(layer "F.Fab")
			(effects
				(font
					(size 0.7 0.7)
					(thickness 0.15)
				)
				(justify right bottom)
			)
		)
		(property "Datasheet" "https://www.murata.com/en-us/products/productdata/8796740059166/ENFA0018.pdf"
			(at 0 0 270)
			(layer "F.Fab")
			(hide yes)
			(effects
				(font
					(size 1.27 1.27)
					(thickness 0.15)
				)
			)
		)
		(property "MPN" "BLM15PD121SN1D"
			(at 0 0 270)
			(unlocked yes)
			(layer "F.Fab")
			(hide yes)
			(effects
				(font
					(size 1 1)
					(thickness 0.15)
				)
			)
		)
		(property "Manufacturer" "Murata"
			(at 0 0 270)
			(unlocked yes)
			(layer "F.Fab")
			(hide yes)
			(effects
				(font
					(size 1 1)
					(thickness 0.15)
				)
			)
		)
		(property "Author" "Antmicro"
			(at 0 0 270)
			(unlocked yes)
			(layer "F.Fab")
			(hide yes)
			(effects
				(font
					(size 1 1)
					(thickness 0.15)
				)
			)
		)
		(property "License" "Apache-2.0"
			(at 0 0 270)
			(unlocked yes)
			(layer "F.Fab")
			(hide yes)
			(effects
				(font
					(size 1 1)
					(thickness 0.15)
				)
			)
		)
		(property "Val" "120Z/1.3A"
			(at 0 0 270)
			(unlocked yes)
			(layer "F.Fab")
			(hide yes)
			(effects
				(font
					(size 1 1)
					(thickness 0.15)
				)
			)
		)
		(property "Current" ""
			(at 0 0 270)
			(unlocked yes)
			(layer "F.Fab")
			(hide yes)
			(effects
				(font
					(size 1 1)
					(thickness 0.15)
				)
			)
		)
		(sheetname "/USB/")
		(sheetfile "usb.kicad_sch")
		(attr smd)
		(fp_rect
			(start -0.925 -0.47)
			(end 0.925 0.47)
			(stroke
				(width 0.05)
				(type default)
			)
			(fill no)
			(layer "F.CrtYd")
		)
		(fp_rect
			(start -0.5 -0.25)
			(end 0.5 0.25)
			(stroke
				(width 0.15)
				(type solid)
			)
			(fill no)
			(layer "F.Fab")
		)
		(fp_text user "${REFERENCE}"
			(at -0.95 3.168 270)
			(layer "F.Fab")
			(effects
				(font
					(size 0.7 0.7)
					(thickness 0.15)
				)
				(justify left bottom)
			)
		)
		(fp_text user "License: Apache-2.0"
			(at -0.95 5.169 270)
			(layer "F.Fab")
			(effects
				(font
					(size 0.7 0.7)
					(thickness 0.15)
				)
				(justify left bottom)
			)
		)
		(fp_text user "Author: Antmicro"
			(at -0.95 4.169 270)
			(layer "F.Fab")
			(effects
				(font
					(size 0.7 0.7)
					(thickness 0.15)
				)
				(justify left bottom)
			)
		)
		(pad "1" smd roundrect
			(at -0.48 0 270)
			(size 0.59 0.64)
			(layers "F.Cu" "F.Mask" "F.Paste")
			(roundrect_rratio 0.25)
			(net 27 "/USB/USB_3V3")
			(pintype "passive")
		)
		(pad "2" smd roundrect
			(at 0.48 0 270)
			(size 0.59 0.64)
			(layers "F.Cu" "F.Mask" "F.Paste")
			(roundrect_rratio 0.25)
			(net 32 "/USB/VCC_USB")
			(pintype "passive")
		)
	)
)
